FILE_TYPE = CONNECTIVITY;
{Allegro Design Entry HDL 17.2-2016 S081 (4005846) 1/11/2022}
"PAGE_NUMBER" = 141;
0"NC";
1"GND\g";
2"GND\g";
3"GND\g";
4"PVDD18_S5_P0\g";
5"GND\g";
6"P3V3_STBY\g";
7"P5V_STBY\g";
8"GND\g";
9"GND\g";
10"GND\g";
11"P3V3_STBY\g";
12"UART_CPU0_SCM_LVC3_UART1_R_RX";
13"UART_CPU0_LVC3_UART0_TX";
14"UART_CPU0_LVC3_UART0_RX";
15"UART_CPU0_UART0_RX";
16"UART_CPU0_UART0_TX";
17"UART_CPU0_SCM_UART1_TX";
18"UART_CPU0_SCM_UART1_RX";
19"PVDD18_S5_P0\g";
20"P3V3_STBY\g";
21"PVDD18_S5_P0\g";
22"UART_LS_EN_N";
23"UART_LS_EN_N";
24"UART_LS_EN";
25"UART_LS_EN_R_N";
26"UART_CPU0_SCM_LVC3_UART1_TX";
27"UART_CPU0_LVC3_UART0_TX";
28"UART_CPU0_LVC3_UART0_RX";
29"UART_VCC_J13";
30"UART_CPU0_LVC3_UART0_R_RX";
31"UART_CPU0_LVC3_UART0_R_TX";
32"UART_CPU0_SCM_LVC3_UART1_R_TX";
33"UART_CPU0_SCM_UART1_R_RX";
34"UART_CPU0_UART0_R_RX";
35"UART_CPU0_UART0_RX";
36"UART_CPU0_UART0_TX";
37"UART_CPU0_SCM_UART1_TX";
38"UART_CPU0_SCM_UART1_RX";
39"UART_CPU0_LVC3_UART0_R_RX";
40"UART_CPU0_LVC3_UART0_TX";
41"UART_CPU0_SCM_LVC3_UART1_R_RX";
42"UART_CPU0_SCM_LVC3_UART1_TX";
%"LSF0204DRUTR"
"1","(-4525,3300)","0","pure_quanta","I117";
;
LOCATION"U116"
$SEC"1"
CDS_SEC"1"
MATERIAL"IC"
PART_NUMBER"AL000204002"
PART_TYPE"SMLF"
VALUE"LSF0204DRUTR"
CDS_LIB"pure_quanta"
CDS_LMAN_SYM_OUTLINE"-225,225,225,-225"
NEEDS_NO_SIZE"TRUE";
"EN# \B"
$PN"12"23;
"GND"
$PN"6"1;
"VREF_B"
$PN"11"20;
"VREF_A"
$PN"1"21;
"B4"
$PN"7"39;
"B3"
$PN"8"31;
"B2"
$PN"9"41;
"B1"
$PN"10"32;
"A4"
$PN"5"34;
"A3"
$PN"4"36;
"A2"
$PN"3"33;
"A1"
$PN"2"37;
%"UNIVERSAL_GND"
"1","(-3950,2925)","2","pure_quanta_power","I118";
;
HDL_POWER"GND"
CDS_LIB"pure_quanta_power";
"A"1;
%"UNIVERSAL_POWER"
"1","(-1350,4175)","0","pure_quanta_power","I120";
;
HDL_POWER"P3V3_STBY"
CDS_LIB"pure_quanta_power";
"A"11;
%"UNIVERSAL_POWER"
"1","(-3975,3975)","0","pure_quanta_power","I128";
;
HDL_POWER"P3V3_STBY"
CDS_LIB"pure_quanta_power";
"A"20;
%"Q_RES"
"1","(-3075,3375)","0","pure_quanta","I131";
;
LOCATION"R1425"
$SEC"1"
CDS_SEC"1"
VALUE"0"
PACK_TYPE"0402LF"
PART_NUMBER"CS00002JB38"
TOLERANCE"5%"
MATERIAL"CHIP"
WATTAGE"1/16W"
CDS_LIB"pure_quanta";
"B"
$PN"2"42;
"A"
$PN"1"32;
%"Q_CAP"
"1","(-3850,3725)","0","pure_quanta","I133";
;
LOCATION"C1354"
$SEC"1"
CDS_SEC"1"
PACK_TYPE"0402"
VOLTAGE"25V"
PART_NUMBER"CH4104K1B00"
VALUE"0.1UF"
TOLERANCE"10%"
MATERIAL"X7R"
CDS_LIB"pure_quanta";
"B"
$PN"2"2;
"A"
$PN"1"20;
%"UNIVERSAL_GND"
"1","(-3850,3525)","2","pure_quanta_power","I134";
;
HDL_POWER"GND"
CDS_LIB"pure_quanta_power";
"A"2;
%"UNIVERSAL_POWER"
"1","(-5050,3950)","0","pure_quanta_power","I135";
;
HDL_POWER"PVDD18_S5_P0"
CDS_LIB"pure_quanta_power";
"A"21;
%"UNIVERSAL_GND"
"1","(-5175,3525)","0","pure_quanta_power","I136";
;
HDL_POWER"GND"
CDS_LIB"pure_quanta_power";
"A"3;
%"Q_CAP"
"1","(-5175,3725)","2","pure_quanta","I137";
;
LOCATION"C1352"
$SEC"1"
CDS_SEC"1"
PACK_TYPE"0402"
VOLTAGE"25V"
PART_NUMBER"CH4104K1B00"
VALUE"0.1UF"
TOLERANCE"10%"
MATERIAL"X7R"
CDS_LIB"pure_quanta";
"B"
$PN"2"3;
"A"
$PN"1"21;
%"UNIVERSAL_POWER"
"1","(-6925,4250)","0","pure_quanta_power","I145";
;
HDL_POWER"PVDD18_S5_P0"
CDS_LIB"pure_quanta_power";
"A"19;
%"Q_RES"
"1","(-5800,3325)","0","pure_quanta","I147";
;
LOCATION"R1423"
$SEC"1"
CDS_SEC"1"
VALUE"0"
PACK_TYPE"0402LF"
PART_NUMBER"CS00002JB38"
TOLERANCE"5%"
MATERIAL"CHIP"
WATTAGE"1/16W"
CDS_LIB"pure_quanta";
"B"
$PN"2"33;
"A"
$PN"1"38;
%"UNIVERSAL_POWER"
"1","(-6875,2750)","0","pure_quanta_power","I148";
;
HDL_POWER"PVDD18_S5_P0"
CDS_LIB"pure_quanta_power";
"A"4;
%"Q_RES"
"1","(-5800,3225)","0","pure_quanta","I176";
;
LOCATION"R817"
$SEC"1"
CDS_SEC"1"
VALUE"0"
PACK_TYPE"0402LF"
PART_NUMBER"CS00002JB38"
TOLERANCE"5%"
MATERIAL"CHIP"
WATTAGE"1/16W"
CDS_LIB"pure_quanta";
"B"
$PN"2"34;
"A"
$PN"1"35;
%"UNIVERSAL_GND"
"1","(-1975,1175)","2","pure_quanta_power","I180";
;
HDL_POWER"GND"
CDS_LIB"pure_quanta_power";
"A"5;
%"UNIVERSAL_POWER"
"1","(-2150,1325)","0","pure_quanta_power","I181";
;
HDL_POWER"P3V3_STBY"
BOM_COST"VR_SYSTEM "
CDS_LIB"pure_quanta_power";
"A"6;
%"P1V0"
"1","(-2375,1325)","0","pure_quanta_power","I182";
;
HDL_POWER"P5V_STBY"
CDS_LIB"pure_quanta_power";
"A"7;
%"Q_RES"
"2","(-2150,1075)","0","pure_quanta","I185";
;
LOCATION"R821"
$SEC"1"
CDS_SEC"1"
PACK_TYPE"0402LF"
VALUE"10K"
TOLERANCE"5%"
MATERIAL"CHIP"
WATTAGE"1/16W"
PART_NUMBER"TMP_QCS31002JB28"
CDS_LIB"pure_quanta";
"A"
$PN"1"6;
"B"
$PN"2"29;
%"Q_RES"
"1","(-2375,1100)","1","pure_quanta","I186";
;
LOCATION"R820"
$SEC"1"
CDS_SEC"1"
PACK_TYPE"0402LF"
VALUE"10K"
TOLERANCE"5%"
MATERIAL"EMPTY"
WATTAGE"1/16W"
PART_NUMBER"TMP_QCS31002JB28"
CDS_LIB"pure_quanta";
"B"
$PN"2"7;
"A"
$PN"1"29;
%"Q_CAP"
"1","(-2575,1150)","0","pure_quanta","I187";
;
LOCATION"C364"
$SEC"1"
CDS_SEC"1"
PACK_TYPE"C0402"
VOLTAGE"50V"
VALUE"220PF"
TOLERANCE"5%"
PART_NUMBER"CH12206JB00"
MATERIAL"C0G"
CDS_LIB"pure_quanta";
"B"
$PN"2"8;
"A"
$PN"1"28;
%"UNIVERSAL_GND"
"1","(-2575,950)","2","pure_quanta_power","I188";
;
HDL_POWER"GND"
CDS_LIB"pure_quanta_power";
"A"8;
%"UNIVERSAL_GND"
"1","(-2775,950)","2","pure_quanta_power","I189";
;
HDL_POWER"GND"
CDS_LIB"pure_quanta_power";
"A"9;
%"Q_CAP"
"1","(-2775,1150)","0","pure_quanta","I190";
;
LOCATION"C363"
$SEC"1"
CDS_SEC"1"
PACK_TYPE"C0402"
VOLTAGE"50V"
VALUE"220PF"
TOLERANCE"5%"
PART_NUMBER"CH12206JB00"
MATERIAL"C0G"
CDS_LIB"pure_quanta";
"B"
$PN"2"9;
"A"
$PN"1"27;
%"Q_RES"
"1","(-3075,3275)","0","pure_quanta","I192";
;
LOCATION"R818"
$SEC"1"
CDS_SEC"1"
VALUE"0"
PACK_TYPE"0402LF"
PART_NUMBER"CS00002JB38"
TOLERANCE"5%"
MATERIAL"CHIP"
WATTAGE"1/16W"
CDS_LIB"pure_quanta";
"B"
$PN"2"40;
"A"
$PN"1"31;
%"CONN4_HFK1040L0P1L7H"
"1","(-1325,1450)","0","pure_quanta","I195";
;
LOCATION"J13"
$SEC"1"
CDS_SEC"1"
PART_NUMBER"DFHD04MS460"
VALUE"CONN4_HFK1040-L0P1L-7H"
MATERIAL"IO"
PART_TYPE"THLF"
NEEDS_NO_SIZE"TRUE"
CDS_LMAN_SYM_OUTLINE"-75,125,75,-125"
CDS_LIB"pure_quanta";
"1"
$PN"1"29;
"2"
$PN"2"28;
"3"
$PN"3"27;
"4"
$PN"4"5;
%"Q_RES"
"2","(-6925,3950)","0","pure_quanta","I196";
;
LOCATION"R816"
$SEC"1"
CDS_SEC"1"
TOLERANCE"5%"
PACK_TYPE"0402LF"
WATTAGE"1/16W"
VALUE"10K"
MATERIAL"CHIP"
CDS_LIB"pure_quanta"
PART_NUMBER"TMP_QCS31002JB28";
"A"
$PN"1"19;
"B"
$PN"2"18;
%"Q_RES"
"2","(-7125,3950)","0","pure_quanta","I197";
;
LOCATION"R815"
$SEC"1"
CDS_SEC"1"
WATTAGE"1/16W"
TOLERANCE"5%"
PACK_TYPE"0402LF"
MATERIAL"EMPTY"
VALUE"10K"
PART_NUMBER"TMP_QCS31002JB28"
CDS_LIB"pure_quanta";
"A"
$PN"1"19;
"B"
$PN"2"17;
%"Q_RES"
"2","(-7350,3950)","0","pure_quanta","I198";
;
LOCATION"R814"
$SEC"1"
CDS_SEC"1"
TOLERANCE"5%"
WATTAGE"1/16W"
MATERIAL"EMPTY"
PACK_TYPE"0402LF"
VALUE"10K"
PART_NUMBER"TMP_QCS31002JB28"
CDS_LIB"pure_quanta";
"A"
$PN"1"19;
"B"
$PN"2"16;
%"Q_RES"
"2","(-7550,3950)","0","pure_quanta","I199";
;
LOCATION"R813"
$SEC"1"
CDS_SEC"1"
TOLERANCE"5%"
VALUE"10K"
WATTAGE"1/16W"
PACK_TYPE"0402LF"
MATERIAL"CHIP"
CDS_LIB"pure_quanta"
PART_NUMBER"TMP_QCS31002JB28";
"A"
$PN"1"19;
"B"
$PN"2"15;
%"Q_RES"
"2","(-725,3900)","0","pure_quanta","I203";
;
LOCATION"R825"
$SEC"1"
CDS_SEC"1"
TOLERANCE"5%"
WATTAGE"1/16W"
MATERIAL"EMPTY"
PACK_TYPE"0402LF"
VALUE"10K"
PART_NUMBER"TMP_QCS31002JB28"
CDS_LIB"pure_quanta";
"A"
$PN"1"11;
"B"
$PN"2"14;
%"Q_RES"
"2","(-925,3900)","0","pure_quanta","I204";
;
LOCATION"R824"
$SEC"1"
CDS_SEC"1"
WATTAGE"1/16W"
TOLERANCE"5%"
VALUE"10K"
PACK_TYPE"0402LF"
MATERIAL"CHIP"
CDS_LIB"pure_quanta"
PART_NUMBER"TMP_QCS31002JB28";
"A"
$PN"1"11;
"B"
$PN"2"13;
%"Q_RES"
"2","(-1150,3900)","0","pure_quanta","I205";
;
LOCATION"R823"
$SEC"1"
CDS_SEC"1"
VALUE"10K"
PACK_TYPE"0402LF"
MATERIAL"EMPTY"
TOLERANCE"5%"
WATTAGE"1/16W"
PART_NUMBER"TMP_QCS31002JB28"
CDS_LIB"pure_quanta";
"A"
$PN"1"11;
"B"
$PN"2"12;
%"Q_RES"
"2","(-1350,3900)","0","pure_quanta","I206";
;
LOCATION"R822"
$SEC"1"
CDS_SEC"1"
PACK_TYPE"0402LF"
WATTAGE"1/16W"
TOLERANCE"5%"
VALUE"10K"
MATERIAL"CHIP"
CDS_LIB"pure_quanta"
PART_NUMBER"TMP_QCS31002JB28";
"A"
$PN"1"11;
"B"
$PN"2"26;
%"Q_RES"
"1","(-6250,2325)","2","pure_quanta","I211";
;
LOCATION"R1253"
$SEC"1"
CDS_SEC"1"
VALUE"33"
ROOM"RST_CPU0_PLD_TO_DIMM"
PACK_TYPE"0402LF"
PART_NUMBER"CS03302JB29"
TOLERANCE"5%"
MATERIAL"CHIP"
WATTAGE"1/16W"
BOM_COST"MEM"
CDS_LIB"pure_quanta";
"B"
$PN"2"25;
"A"
$PN"1"22;
%"Q_RES"
"1","(-2950,1425)","0","pure_quanta","I212";
;
LOCATION"R819"
$SEC"1"
CDS_SEC"1"
VALUE"0"
PACK_TYPE"0402LF"
PART_NUMBER"CS00002JB38"
TOLERANCE"5%"
MATERIAL"CHIP"
WATTAGE"1/16W"
CDS_LIB"pure_quanta";
"B"
$PN"2"28;
"A"
$PN"1"30;
%"MOSFET_N_GSD"
"1","(-6900,2025)","0","pure_quanta","I89";
;
LOCATION"Q61"
$SEC"1"
CDS_SEC"1"
VALUE"NX138BK"
PART_NUMBER"BAM01380023"
PART_TYPE"SMLF"
MATERIAL"IC"
NEEDS_NO_SIZE"TRUE"
CDS_LMAN_SYM_OUTLINE"-100,100,100,-100"
CDS_LIB"pure_quanta";
"DRAIN"
$PN"D"25;
"SOURCE"
$PN"S"10;
"GATE"
$PN"G"24;
%"UNIVERSAL_GND"
"1","(-6875,1675)","2","pure_quanta_power","I90";
;
HDL_POWER"GND"
CDS_LIB"pure_quanta_power";
"A"10;
%"Q_RES"
"2","(-6875,2550)","0","pure_quanta","I91";
;
LOCATION"R1419"
$SEC"1"
CDS_SEC"1"
TOLERANCE"5%"
PACK_TYPE"0402LF"
MATERIAL"CHIP"
WATTAGE"1/16W"
VALUE"4.7K"
PART_NUMBER"TMP_QCS24702JB38"
CDS_LIB"pure_quanta";
"A"
$PN"1"4;
"B"
$PN"2"25;
END.
